(kicad_pcb
	(version 20260206)
	(generator "pcbnew")
	(generator_version "10.0")
	(general
		(thickness 1.6)
		(legacy_teardrops no)
	)
	(paper "A4")
	(title_block
		(title "01162023_DA0F0TEBIF0_F0T_Expander_BD_F_brd_V02_OCP.brd")
		(comment 1 "Grand Teton / footprints 1051-1059 of 9728")
	)
	(layers
		(0 "F.Cu" signal "TOP")
		(4 "In1.Cu" signal "GND")
		(6 "In2.Cu" signal "VCC")
		(8 "In3.Cu" signal "VCC1")
		(10 "In4.Cu" signal "GND1")
		(12 "In5.Cu" signal "IN1")
		(14 "In6.Cu" signal "GND2")
		(16 "In7.Cu" signal "IN2")
		(18 "In8.Cu" signal "GND3")
		(20 "In9.Cu" signal "IN3")
		(22 "In10.Cu" signal "GND4")
		(24 "In11.Cu" signal "IN4")
		(26 "In12.Cu" signal "GND5")
		(28 "In13.Cu" signal "IN5")
		(30 "In14.Cu" signal "GND6")
		(32 "In15.Cu" signal "IN6")
		(34 "In16.Cu" signal "GND7")
		(2 "B.Cu" signal "BOTTOM")
		(9 "F.Adhes" user "F.Adhesive")
		(11 "B.Adhes" user "B.Adhesive")
		(13 "F.Paste" user "Package Geometry/Pastemask Top")
		(15 "B.Paste" user "Package Geometry/Pastemask Bottom")
		(5 "F.SilkS" user "Ref Des/Silkscreen Top")
		(7 "B.SilkS" user "Ref Des/Silkscreen Bottom")
		(1 "F.Mask" user "Board Geometry/Soldermask Top")
		(3 "B.Mask" user "Board Geometry/Soldermask Bottom")
		(17 "Dwgs.User" user "User.Drawings")
		(19 "Cmts.User" user "User.Comments")
		(21 "Eco1.User" user "User.Eco1")
		(23 "Eco2.User" user "User.Eco2")
		(25 "Edge.Cuts" user "Board Geometry/Outline")
		(27 "Margin" user)
		(31 "F.CrtYd" user "Package Geometry/Place Bound Top")
		(29 "B.CrtYd" user "Package Geometry/Place Bound Bottom")
		(35 "F.Fab" user "Ref Des/Assembly Top")
		(33 "B.Fab" user "Ref Des/Assembly Bottom")
	)
	(footprint ""
		(layer "F.Cu")
		(at 33.319974 -20.72005)
		(property "Reference" "H108"
			(at 4.382262 2.165858 0)
			(unlocked yes)
			(layer "B.SilkS")
			(effects
				(font
					(size 0.7874 0.5842)
					(thickness 0.1524)
				)
				(justify left mirror)
			)
		)
		(property "Value" ""
			(at 0 0 0)
			(layer "F.Fab")
			(effects
				(font
					(size 1.27 1.27)
				)
			)
		)
		(duplicate_pad_numbers_are_jumpers no)
		(pad "1" thru_hole rect
			(at 0 0)
			(size 4.2164 5.0038)
			(drill 2.0066
				(offset 0.099822 0)
			)
			(layers "*.Cu" "*.Mask")
			(remove_unused_layers no)
			(net "Net_8555")
			(clearance -0.8509)
			(padstack
				(mode front_inner_back)
				(layer "Inner"
					(shape circle)
					(size 4.0132 4.0132)
					(clearance -0.7493)
				)
				(layer "B.Cu"
					(shape circle)
					(size 4.0132 4.0132)
					(clearance -0.7493)
				)
			)
		)
	)
	(footprint ""
		(layer "F.Cu")
		(at 375.426224 -37.929566 90)
		(property "Reference" "R5573"
			(at 0 0 90)
			(layer "F.SilkS")
			(hide yes)
			(effects
				(font
					(size 1.27 1.27)
				)
			)
		)
		(property "Value" ""
			(at 0 0 90)
			(layer "F.Fab")
			(effects
				(font
					(size 1.27 1.27)
				)
			)
		)
		(duplicate_pad_numbers_are_jumpers no)
		(fp_line
			(start 0.7874 -0.4064)
			(end 0.7874 0.4064)
			(stroke
				(width 0.1524)
				(type default)
			)
			(layer "F.SilkS")
		)
		(fp_line
			(start -0.7874 -0.4064)
			(end 0.7874 -0.4064)
			(stroke
				(width 0.1524)
				(type default)
			)
			(layer "F.SilkS")
		)
		(fp_line
			(start 0.7874 0.4064)
			(end -0.7874 0.4064)
			(stroke
				(width 0.1524)
				(type default)
			)
			(layer "F.SilkS")
		)
		(fp_line
			(start -0.7874 0.4064)
			(end -0.7874 -0.4064)
			(stroke
				(width 0.1524)
				(type default)
			)
			(layer "F.SilkS")
		)
		(fp_line
			(start -0.12065 -0.305054)
			(end -0.12065 -0.2794)
			(stroke
				(width 0.1)
				(type default)
			)
			(layer "F.Fab")
		)
		(fp_line
			(start -0.67945 -0.305054)
			(end -0.12065 -0.305054)
			(stroke
				(width 0.1)
				(type default)
			)
			(layer "F.Fab")
		)
		(fp_line
			(start 0.67945 -0.3048)
			(end 0.67945 0.3048)
			(stroke
				(width 0.1)
				(type default)
			)
			(layer "F.Fab")
		)
		(fp_line
			(start 0.12065 -0.3048)
			(end 0.67945 -0.3048)
			(stroke
				(width 0.1)
				(type default)
			)
			(layer "F.Fab")
		)
		(fp_line
			(start 0.12065 -0.2794)
			(end 0.12065 -0.3048)
			(stroke
				(width 0.1)
				(type default)
			)
			(layer "F.Fab")
		)
		(fp_line
			(start -0.12065 -0.2794)
			(end 0.12065 -0.2794)
			(stroke
				(width 0.1)
				(type default)
			)
			(layer "F.Fab")
		)
		(fp_line
			(start 0.120396 0.2794)
			(end -0.12065 0.2794)
			(stroke
				(width 0.1)
				(type default)
			)
			(layer "F.Fab")
		)
		(fp_line
			(start -0.12065 0.2794)
			(end -0.12065 0.3048)
			(stroke
				(width 0.1)
				(type default)
			)
			(layer "F.Fab")
		)
		(fp_line
			(start 0.67945 0.3048)
			(end 0.120396 0.3048)
			(stroke
				(width 0.1)
				(type default)
			)
			(layer "F.Fab")
		)
		(fp_line
			(start 0.120396 0.3048)
			(end 0.120396 0.2794)
			(stroke
				(width 0.1)
				(type default)
			)
			(layer "F.Fab")
		)
		(fp_line
			(start -0.12065 0.3048)
			(end -0.67945 0.3048)
			(stroke
				(width 0.1)
				(type default)
			)
			(layer "F.Fab")
		)
		(fp_line
			(start -0.67945 0.3048)
			(end -0.67945 -0.305054)
			(stroke
				(width 0.1)
				(type default)
			)
			(layer "F.Fab")
		)
		(pad "1" smd circle
			(at -0.40005 0 90)
			(size 0 0)
			(layers "F.Cu" "F.Mask" "F.Paste")
			(net "SSD13_AUX_P3V3_EN_R")
		)
		(pad "2" smd circle
			(at 0.40005 0 90)
			(size 0 0)
			(layers "F.Cu" "F.Mask" "F.Paste")
			(net "SSD13_AUX_P3V3_EN")
		)
	)
	(footprint ""
		(layer "F.Cu")
		(at 213.935056 -214.32266)
		(property "Reference" "R4878"
			(at 0 0 0)
			(layer "F.SilkS")
			(hide yes)
			(effects
				(font
					(size 1.27 1.27)
				)
			)
		)
		(property "Value" ""
			(at 0 0 0)
			(layer "F.Fab")
			(effects
				(font
					(size 1.27 1.27)
				)
			)
		)
		(duplicate_pad_numbers_are_jumpers no)
		(fp_line
			(start -0.7874 -0.4064)
			(end 0.7874 -0.4064)
			(stroke
				(width 0.1524)
				(type default)
			)
			(layer "F.SilkS")
		)
		(fp_line
			(start -0.7874 0.4064)
			(end -0.7874 -0.4064)
			(stroke
				(width 0.1524)
				(type default)
			)
			(layer "F.SilkS")
		)
		(fp_line
			(start 0.7874 -0.4064)
			(end 0.7874 0.4064)
			(stroke
				(width 0.1524)
				(type default)
			)
			(layer "F.SilkS")
		)
		(fp_line
			(start 0.7874 0.4064)
			(end -0.7874 0.4064)
			(stroke
				(width 0.1524)
				(type default)
			)
			(layer "F.SilkS")
		)
		(fp_line
			(start -0.67945 -0.305054)
			(end -0.12065 -0.305054)
			(stroke
				(width 0.1)
				(type default)
			)
			(layer "F.Fab")
		)
		(fp_line
			(start -0.67945 0.3048)
			(end -0.67945 -0.305054)
			(stroke
				(width 0.1)
				(type default)
			)
			(layer "F.Fab")
		)
		(fp_line
			(start -0.12065 -0.305054)
			(end -0.12065 -0.2794)
			(stroke
				(width 0.1)
				(type default)
			)
			(layer "F.Fab")
		)
		(fp_line
			(start -0.12065 -0.2794)
			(end 0.12065 -0.2794)
			(stroke
				(width 0.1)
				(type default)
			)
			(layer "F.Fab")
		)
		(fp_line
			(start -0.12065 0.2794)
			(end -0.12065 0.3048)
			(stroke
				(width 0.1)
				(type default)
			)
			(layer "F.Fab")
		)
		(fp_line
			(start -0.12065 0.3048)
			(end -0.67945 0.3048)
			(stroke
				(width 0.1)
				(type default)
			)
			(layer "F.Fab")
		)
		(fp_line
			(start 0.120396 0.2794)
			(end -0.12065 0.2794)
			(stroke
				(width 0.1)
				(type default)
			)
			(layer "F.Fab")
		)
		(fp_line
			(start 0.120396 0.3048)
			(end 0.120396 0.2794)
			(stroke
				(width 0.1)
				(type default)
			)
			(layer "F.Fab")
		)
		(fp_line
			(start 0.12065 -0.3048)
			(end 0.67945 -0.3048)
			(stroke
				(width 0.1)
				(type default)
			)
			(layer "F.Fab")
		)
		(fp_line
			(start 0.12065 -0.2794)
			(end 0.12065 -0.3048)
			(stroke
				(width 0.1)
				(type default)
			)
			(layer "F.Fab")
		)
		(fp_line
			(start 0.67945 -0.3048)
			(end 0.67945 0.3048)
			(stroke
				(width 0.1)
				(type default)
			)
			(layer "F.Fab")
		)
		(fp_line
			(start 0.67945 0.3048)
			(end 0.120396 0.3048)
			(stroke
				(width 0.1)
				(type default)
			)
			(layer "F.Fab")
		)
		(pad "1" smd circle
			(at -0.40005 0)
			(size 0 0)
			(layers "F.Cu" "F.Mask" "F.Paste")
			(net "P1V2_AUX")
		)
		(pad "2" smd circle
			(at 0.40005 0)
			(size 0 0)
			(layers "F.Cu" "F.Mask" "F.Paste")
			(net "SMB_NIC6_SDA")
		)
	)
	(footprint ""
		(layer "F.Cu")
		(at 72.483726 -6.897624)
		(property "Reference" "R5808"
			(at 0 0 0)
			(layer "F.SilkS")
			(hide yes)
			(effects
				(font
					(size 1.27 1.27)
				)
			)
		)
		(property "Value" ""
			(at 0 0 0)
			(layer "F.Fab")
			(effects
				(font
					(size 1.27 1.27)
				)
			)
		)
		(duplicate_pad_numbers_are_jumpers no)
		(fp_line
			(start -0.7874 -0.4064)
			(end 0.7874 -0.4064)
			(stroke
				(width 0.1524)
				(type default)
			)
			(layer "F.SilkS")
		)
		(fp_line
			(start -0.7874 0.4064)
			(end -0.7874 -0.4064)
			(stroke
				(width 0.1524)
				(type default)
			)
			(layer "F.SilkS")
		)
		(fp_line
			(start 0.7874 -0.4064)
			(end 0.7874 0.4064)
			(stroke
				(width 0.1524)
				(type default)
			)
			(layer "F.SilkS")
		)
		(fp_line
			(start 0.7874 0.4064)
			(end -0.7874 0.4064)
			(stroke
				(width 0.1524)
				(type default)
			)
			(layer "F.SilkS")
		)
		(fp_line
			(start -0.67945 -0.305054)
			(end -0.12065 -0.305054)
			(stroke
				(width 0.1)
				(type default)
			)
			(layer "F.Fab")
		)
		(fp_line
			(start -0.67945 0.3048)
			(end -0.67945 -0.305054)
			(stroke
				(width 0.1)
				(type default)
			)
			(layer "F.Fab")
		)
		(fp_line
			(start -0.12065 -0.305054)
			(end -0.12065 -0.2794)
			(stroke
				(width 0.1)
				(type default)
			)
			(layer "F.Fab")
		)
		(fp_line
			(start -0.12065 -0.2794)
			(end 0.12065 -0.2794)
			(stroke
				(width 0.1)
				(type default)
			)
			(layer "F.Fab")
		)
		(fp_line
			(start -0.12065 0.2794)
			(end -0.12065 0.3048)
			(stroke
				(width 0.1)
				(type default)
			)
			(layer "F.Fab")
		)
		(fp_line
			(start -0.12065 0.3048)
			(end -0.67945 0.3048)
			(stroke
				(width 0.1)
				(type default)
			)
			(layer "F.Fab")
		)
		(fp_line
			(start 0.120396 0.2794)
			(end -0.12065 0.2794)
			(stroke
				(width 0.1)
				(type default)
			)
			(layer "F.Fab")
		)
		(fp_line
			(start 0.120396 0.3048)
			(end 0.120396 0.2794)
			(stroke
				(width 0.1)
				(type default)
			)
			(layer "F.Fab")
		)
		(fp_line
			(start 0.12065 -0.3048)
			(end 0.67945 -0.3048)
			(stroke
				(width 0.1)
				(type default)
			)
			(layer "F.Fab")
		)
		(fp_line
			(start 0.12065 -0.2794)
			(end 0.12065 -0.3048)
			(stroke
				(width 0.1)
				(type default)
			)
			(layer "F.Fab")
		)
		(fp_line
			(start 0.67945 -0.3048)
			(end 0.67945 0.3048)
			(stroke
				(width 0.1)
				(type default)
			)
			(layer "F.Fab")
		)
		(fp_line
			(start 0.67945 0.3048)
			(end 0.120396 0.3048)
			(stroke
				(width 0.1)
				(type default)
			)
			(layer "F.Fab")
		)
		(pad "1" smd circle
			(at -0.40005 0)
			(size 0 0)
			(layers "F.Cu" "F.Mask" "F.Paste")
			(net "SMB_BIC_I2C6_MUX_THERMAL_R_SDA")
		)
		(pad "2" smd circle
			(at 0.40005 0)
			(size 0 0)
			(layers "F.Cu" "F.Mask" "F.Paste")
			(net "SMB_LM75_2_SDA")
		)
	)
	(footprint ""
		(layer "F.Cu")
		(at 428.319438 -123.184666 180)
		(property "Reference" "C660"
			(at 0 0 180)
			(layer "F.SilkS")
			(hide yes)
			(effects
				(font
					(size 1.27 1.27)
				)
			)
		)
		(property "Value" ""
			(at 0 0 180)
			(layer "F.Fab")
			(effects
				(font
					(size 1.27 1.27)
				)
			)
		)
		(duplicate_pad_numbers_are_jumpers no)
		(fp_line
			(start 0.299974 0.150114)
			(end -0.299974 0.150114)
			(stroke
				(width 0.1)
				(type default)
			)
			(layer "F.Fab")
		)
		(fp_line
			(start 0.299974 -0.150114)
			(end 0.299974 0.150114)
			(stroke
				(width 0.1)
				(type default)
			)
			(layer "F.Fab")
		)
		(fp_line
			(start -0.299974 0.150114)
			(end -0.299974 -0.150114)
			(stroke
				(width 0.1)
				(type default)
			)
			(layer "F.Fab")
		)
		(fp_line
			(start -0.299974 -0.150114)
			(end 0.299974 -0.150114)
			(stroke
				(width 0.1)
				(type default)
			)
			(layer "F.Fab")
		)
		(pad "1" smd rect
			(at -0.2667 0 180)
			(size 0.3048 0.381)
			(layers "F.Cu" "F.Mask" "F.Paste")
			(net "P5E_PEX3_STN0_TX_DP<2>")
		)
		(pad "2" smd rect
			(at 0.2667 0 180)
			(size 0.3048 0.381)
			(layers "F.Cu" "F.Mask" "F.Paste")
			(net "P5E_PEX3_STN0_TX_C_DP<2>")
		)
	)
	(footprint ""
		(layer "F.Cu")
		(at 460.340964 -521.743686 180)
		(property "Reference" "SCREW_4"
			(at -3.2385 -1.402334 0)
			(unlocked yes)
			(layer "B.SilkS")
			(effects
				(font
					(size 0.7874 0.5842)
					(thickness 0.1524)
				)
				(justify mirror)
			)
		)
		(property "Value" ""
			(at 0 0 180)
			(layer "F.Fab")
			(effects
				(font
					(size 1.27 1.27)
				)
			)
		)
		(duplicate_pad_numbers_are_jumpers no)
		(pad "1" thru_hole circle
			(at 0 0 180)
			(size 0.4572 0.4572)
			(drill 0.2032)
			(layers "*.Cu" "*.Mask")
			(remove_unused_layers no)
			(net "Net_9160")
			(clearance 0.127)
			(thermal_gap 0.127)
			(padstack
				(mode front_inner_back)
				(layer "Inner"
					(shape circle)
					(size 0.4572 0.4572)
					(clearance 0.127)
				)
				(layer "B.Cu"
					(shape circle)
					(size 0.508 0.508)
					(clearance 0.1016)
				)
			)
		)
	)
	(footprint ""
		(layer "F.Cu")
		(at 26.952702 -262.649208 90)
		(property "Reference" "C3016"
			(at 0 0 90)
			(layer "F.SilkS")
			(hide yes)
			(effects
				(font
					(size 1.27 1.27)
				)
			)
		)
		(property "Value" ""
			(at 0 0 90)
			(layer "F.Fab")
			(effects
				(font
					(size 1.27 1.27)
				)
			)
		)
		(duplicate_pad_numbers_are_jumpers no)
		(fp_line
			(start 0.299974 -0.150114)
			(end 0.299974 0.150114)
			(stroke
				(width 0.1)
				(type default)
			)
			(layer "F.Fab")
		)
		(fp_line
			(start -0.299974 -0.150114)
			(end 0.299974 -0.150114)
			(stroke
				(width 0.1)
				(type default)
			)
			(layer "F.Fab")
		)
		(fp_line
			(start 0.299974 0.150114)
			(end -0.299974 0.150114)
			(stroke
				(width 0.1)
				(type default)
			)
			(layer "F.Fab")
		)
		(fp_line
			(start -0.299974 0.150114)
			(end -0.299974 -0.150114)
			(stroke
				(width 0.1)
				(type default)
			)
			(layer "F.Fab")
		)
		(pad "1" smd rect
			(at -0.2667 0 90)
			(size 0.3048 0.381)
			(layers "F.Cu" "F.Mask" "F.Paste")
			(net "P1V8_PLL0_PEX0")
		)
		(pad "2" smd rect
			(at 0.2667 0 90)
			(size 0.3048 0.381)
			(layers "F.Cu" "F.Mask" "F.Paste")
			(net "GND")
		)
	)
	(footprint ""
		(layer "F.Cu")
		(at 446.734438 -33.631886 180)
		(property "Reference" "C723"
			(at 0 0 180)
			(layer "F.SilkS")
			(hide yes)
			(effects
				(font
					(size 1.27 1.27)
				)
			)
		)
		(property "Value" ""
			(at 0 0 180)
			(layer "F.Fab")
			(effects
				(font
					(size 1.27 1.27)
				)
			)
		)
		(duplicate_pad_numbers_are_jumpers no)
		(fp_line
			(start 0.299974 0.150114)
			(end -0.299974 0.150114)
			(stroke
				(width 0.1)
				(type default)
			)
			(layer "F.Fab")
		)
		(fp_line
			(start 0.299974 -0.150114)
			(end 0.299974 0.150114)
			(stroke
				(width 0.1)
				(type default)
			)
			(layer "F.Fab")
		)
		(fp_line
			(start -0.299974 0.150114)
			(end -0.299974 -0.150114)
			(stroke
				(width 0.1)
				(type default)
			)
			(layer "F.Fab")
		)
		(fp_line
			(start -0.299974 -0.150114)
			(end 0.299974 -0.150114)
			(stroke
				(width 0.1)
				(type default)
			)
			(layer "F.Fab")
		)
		(pad "1" smd rect
			(at -0.2667 0 180)
			(size 0.3048 0.381)
			(layers "F.Cu" "F.Mask" "F.Paste")
			(net "P5E_PEX3_STN2_TX_DN<35>")
		)
		(pad "2" smd rect
			(at 0.2667 0 180)
			(size 0.3048 0.381)
			(layers "F.Cu" "F.Mask" "F.Paste")
			(net "P5E_PEX3_STN2_TX_C_DN<35>")
		)
	)
	(footprint ""
		(layer "F.Cu")
		(at 347.966792 -240.691162 90)
		(property "Reference" "R3527"
			(at 0 0 90)
			(layer "F.SilkS")
			(hide yes)
			(effects
				(font
					(size 1.27 1.27)
				)
			)
		)
		(property "Value" ""
			(at 0 0 90)
			(layer "F.Fab")
			(effects
				(font
					(size 1.27 1.27)
				)
			)
		)
		(duplicate_pad_numbers_are_jumpers no)
		(fp_line
			(start 0.7874 -0.4064)
			(end 0.7874 0.4064)
			(stroke
				(width 0.1524)
				(type default)
			)
			(layer "F.SilkS")
		)
		(fp_line
			(start -0.7874 -0.4064)
			(end 0.7874 -0.4064)
			(stroke
				(width 0.1524)
				(type default)
			)
			(layer "F.SilkS")
		)
		(fp_line
			(start 0.7874 0.4064)
			(end -0.7874 0.4064)
			(stroke
				(width 0.1524)
				(type default)
			)
			(layer "F.SilkS")
		)
		(fp_line
			(start -0.7874 0.4064)
			(end -0.7874 -0.4064)
			(stroke
				(width 0.1524)
				(type default)
			)
			(layer "F.SilkS")
		)
		(fp_line
			(start -0.12065 -0.305054)
			(end -0.12065 -0.2794)
			(stroke
				(width 0.1)
				(type default)
			)
			(layer "F.Fab")
		)
		(fp_line
			(start -0.67945 -0.305054)
			(end -0.12065 -0.305054)
			(stroke
				(width 0.1)
				(type default)
			)
			(layer "F.Fab")
		)
		(fp_line
			(start 0.67945 -0.3048)
			(end 0.67945 0.3048)
			(stroke
				(width 0.1)
				(type default)
			)
			(layer "F.Fab")
		)
		(fp_line
			(start 0.12065 -0.3048)
			(end 0.67945 -0.3048)
			(stroke
				(width 0.1)
				(type default)
			)
			(layer "F.Fab")
		)
		(fp_line
			(start 0.12065 -0.2794)
			(end 0.12065 -0.3048)
			(stroke
				(width 0.1)
				(type default)
			)
			(layer "F.Fab")
		)
		(fp_line
			(start -0.12065 -0.2794)
			(end 0.12065 -0.2794)
			(stroke
				(width 0.1)
				(type default)
			)
			(layer "F.Fab")
		)
		(fp_line
			(start 0.120396 0.2794)
			(end -0.12065 0.2794)
			(stroke
				(width 0.1)
				(type default)
			)
			(layer "F.Fab")
		)
		(fp_line
			(start -0.12065 0.2794)
			(end -0.12065 0.3048)
			(stroke
				(width 0.1)
				(type default)
			)
			(layer "F.Fab")
		)
		(fp_line
			(start 0.67945 0.3048)
			(end 0.120396 0.3048)
			(stroke
				(width 0.1)
				(type default)
			)
			(layer "F.Fab")
		)
		(fp_line
			(start 0.120396 0.3048)
			(end 0.120396 0.2794)
			(stroke
				(width 0.1)
				(type default)
			)
			(layer "F.Fab")
		)
		(fp_line
			(start -0.12065 0.3048)
			(end -0.67945 0.3048)
			(stroke
				(width 0.1)
				(type default)
			)
			(layer "F.Fab")
		)
		(fp_line
			(start -0.67945 0.3048)
			(end -0.67945 -0.305054)
			(stroke
				(width 0.1)
				(type default)
			)
			(layer "F.Fab")
		)
		(pad "1" smd circle
			(at -0.40005 0 90)
			(size 0 0)
			(layers "F.Cu" "F.Mask" "F.Paste")
			(net "SSD2_CLK_EN_N")
		)
		(pad "2" smd circle
			(at 0.40005 0 90)
			(size 0 0)
			(layers "F.Cu" "F.Mask" "F.Paste")
			(net "SSD2_CLK_EN_R_N")
		)
	)
)
